# S9S_MB_2U (Grand Teton) — schematic netlist excerpt (pin names and nets, part order shuffled) for the footprints in the layout excerpt that follows; sources: Cadence DE-HDL packaged netlist, KiCad conversion of 03242023_DA0F0TMBIJ0_F0T_Motherboard_J_brd_V01_OCP.brd

PC376  Q_CAP  100NF 50V 10% X7R  pkg C0402  page 297 : A = SW_PVCCD_HV_CPU1_BOOT1_R ; B = SW_PVCCD_HV_CPU1_BOOTR1
R1448  Q_RES  33.2 1% CHIP  pkg 0402LF  page 222 : A = FM_CPU1_SKTOCC_LVT3_N ; B = FM_CPU1_SKTOCC_LVT3_PLD_N

(kicad_pcb
	(version 20260206)
	(generator "pcbnew")
	(generator_version "10.0")
	(general
		(thickness 1.6)
		(legacy_teardrops no)
	)
	(paper "A4")
	(title_block
		(title "03242023_DA0F0TMBIJ0_F0T_Motherboard_J_brd_V01_OCP.brd")
		(comment 1 "Grand Teton / footprints 1534-1535 of 6105")
	)
	(layers
		(0 "F.Cu" signal "TOP")
		(4 "In1.Cu" signal "GND")
		(6 "In2.Cu" signal "IN1")
		(8 "In3.Cu" signal "GND1")
		(10 "In4.Cu" signal "IN2")
		(12 "In5.Cu" signal "GND2")
		(14 "In6.Cu" signal "IN3")
		(16 "In7.Cu" signal "GND3")
		(18 "In8.Cu" signal "VCC")
		(20 "In9.Cu" signal "VCC1")
		(22 "In10.Cu" signal "GND4")
		(24 "In11.Cu" signal "IN4")
		(26 "In12.Cu" signal "GND5")
		(28 "In13.Cu" signal "IN5")
		(30 "In14.Cu" signal "GND6")
		(32 "In15.Cu" signal "IN6")
		(34 "In16.Cu" signal "GND7")
		(2 "B.Cu" signal "BOTTOM")
		(9 "F.Adhes" user "F.Adhesive")
		(11 "B.Adhes" user "B.Adhesive")
		(13 "F.Paste" user "Package Geometry/Pastemask Top")
		(15 "B.Paste" user "Package Geometry/Pastemask Bottom")
		(5 "F.SilkS" user "Ref Des/Silkscreen Top")
		(7 "B.SilkS" user "Ref Des/Silkscreen Bottom")
		(1 "F.Mask" user "Board Geometry/Soldermask Top")
		(3 "B.Mask" user "Board Geometry/Soldermask Bottom")
		(17 "Dwgs.User" user "User.Drawings")
		(19 "Cmts.User" user "User.Comments")
		(21 "Eco1.User" user "User.Eco1")
		(23 "Eco2.User" user "User.Eco2")
		(25 "Edge.Cuts" user "Board Geometry/Outline")
		(27 "Margin" user)
		(31 "F.CrtYd" user "Package Geometry/Place Bound Top")
		(29 "B.CrtYd" user "Package Geometry/Place Bound Bottom")
		(35 "F.Fab" user "Ref Des/Assembly Top")
		(33 "B.Fab" user "Ref Des/Assembly Bottom")
	)
	(footprint ""
		(layer "F.Cu")
		(at 50.437542 -166.847266)
		(property "Reference" "PC376"
			(at 0 0 0)
			(layer "F.SilkS")
			(hide yes)
			(effects
				(font
					(size 1.27 1.27)
				)
			)
		)
		(property "Value" ""
			(at 0 0 0)
			(layer "F.Fab")
			(effects
				(font
					(size 1.27 1.27)
				)
			)
		)
		(duplicate_pad_numbers_are_jumpers no)
		(fp_line
			(start -0.7874 -0.4064)
			(end 0.7874 -0.4064)
			(stroke
				(width 0.1524)
				(type default)
			)
			(layer "F.SilkS")
		)
		(fp_line
			(start -0.7874 0.4064)
			(end -0.7874 -0.4064)
			(stroke
				(width 0.1524)
				(type default)
			)
			(layer "F.SilkS")
		)
		(fp_line
			(start 0.7874 -0.4064)
			(end 0.7874 0.4064)
			(stroke
				(width 0.1524)
				(type default)
			)
			(layer "F.SilkS")
		)
		(fp_line
			(start 0.7874 0.4064)
			(end -0.7874 0.4064)
			(stroke
				(width 0.1524)
				(type default)
			)
			(layer "F.SilkS")
		)
		(fp_line
			(start -0.67945 -0.305054)
			(end -0.12065 -0.305054)
			(stroke
				(width 0.1)
				(type default)
			)
			(layer "F.Fab")
		)
		(fp_line
			(start -0.67945 0.3048)
			(end -0.67945 -0.305054)
			(stroke
				(width 0.1)
				(type default)
			)
			(layer "F.Fab")
		)
		(fp_line
			(start -0.12065 -0.305054)
			(end -0.12065 -0.2794)
			(stroke
				(width 0.1)
				(type default)
			)
			(layer "F.Fab")
		)
		(fp_line
			(start -0.12065 -0.2794)
			(end 0.12065 -0.2794)
			(stroke
				(width 0.1)
				(type default)
			)
			(layer "F.Fab")
		)
		(fp_line
			(start -0.12065 0.2794)
			(end -0.12065 0.3048)
			(stroke
				(width 0.1)
				(type default)
			)
			(layer "F.Fab")
		)
		(fp_line
			(start -0.12065 0.3048)
			(end -0.67945 0.3048)
			(stroke
				(width 0.1)
				(type default)
			)
			(layer "F.Fab")
		)
		(fp_line
			(start 0.120396 0.2794)
			(end -0.12065 0.2794)
			(stroke
				(width 0.1)
				(type default)
			)
			(layer "F.Fab")
		)
		(fp_line
			(start 0.120396 0.3048)
			(end 0.120396 0.2794)
			(stroke
				(width 0.1)
				(type default)
			)
			(layer "F.Fab")
		)
		(fp_line
			(start 0.12065 -0.3048)
			(end 0.67945 -0.3048)
			(stroke
				(width 0.1)
				(type default)
			)
			(layer "F.Fab")
		)
		(fp_line
			(start 0.12065 -0.2794)
			(end 0.12065 -0.3048)
			(stroke
				(width 0.1)
				(type default)
			)
			(layer "F.Fab")
		)
		(fp_line
			(start 0.67945 -0.3048)
			(end 0.67945 0.3048)
			(stroke
				(width 0.1)
				(type default)
			)
			(layer "F.Fab")
		)
		(fp_line
			(start 0.67945 0.3048)
			(end 0.120396 0.3048)
			(stroke
				(width 0.1)
				(type default)
			)
			(layer "F.Fab")
		)
		(pad "1" smd circle
			(at -0.40005 0)
			(size 0 0)
			(layers "F.Cu" "F.Mask" "F.Paste")
			(net "SW_PVCCD_HV_CPU1_BOOT1_R")
		)
		(pad "2" smd circle
			(at 0.40005 0)
			(size 0 0)
			(layers "F.Cu" "F.Mask" "F.Paste")
			(net "SW_PVCCD_HV_CPU1_BOOTR1")
		)
	)
	(footprint ""
		(layer "F.Cu")
		(at 179.12588 -133.695948 -90)
		(property "Reference" "R1448"
			(at 0 0 270)
			(layer "F.SilkS")
			(hide yes)
			(effects
				(font
					(size 1.27 1.27)
				)
			)
		)
		(property "Value" ""
			(at 0 0 270)
			(layer "F.Fab")
			(effects
				(font
					(size 1.27 1.27)
				)
			)
		)
		(duplicate_pad_numbers_are_jumpers no)
		(fp_line
			(start -0.7874 0.4064)
			(end -0.7874 -0.4064)
			(stroke
				(width 0.1524)
				(type default)
			)
			(layer "F.SilkS")
		)
		(fp_line
			(start 0.7874 0.4064)
			(end -0.7874 0.4064)
			(stroke
				(width 0.1524)
				(type default)
			)
			(layer "F.SilkS")
		)
		(fp_line
			(start -0.7874 -0.4064)
			(end 0.7874 -0.4064)
			(stroke
				(width 0.1524)
				(type default)
			)
			(layer "F.SilkS")
		)
		(fp_line
			(start 0.7874 -0.4064)
			(end 0.7874 0.4064)
			(stroke
				(width 0.1524)
				(type default)
			)
			(layer "F.SilkS")
		)
		(fp_line
			(start -0.67945 0.3048)
			(end -0.67945 -0.305054)
			(stroke
				(width 0.1)
				(type default)
			)
			(layer "F.Fab")
		)
		(fp_line
			(start -0.12065 0.3048)
			(end -0.67945 0.3048)
			(stroke
				(width 0.1)
				(type default)
			)
			(layer "F.Fab")
		)
		(fp_line
			(start 0.120396 0.3048)
			(end 0.120396 0.2794)
			(stroke
				(width 0.1)
				(type default)
			)
			(layer "F.Fab")
		)
		(fp_line
			(start 0.67945 0.3048)
			(end 0.120396 0.3048)
			(stroke
				(width 0.1)
				(type default)
			)
			(layer "F.Fab")
		)
		(fp_line
			(start -0.12065 0.2794)
			(end -0.12065 0.3048)
			(stroke
				(width 0.1)
				(type default)
			)
			(layer "F.Fab")
		)
		(fp_line
			(start 0.120396 0.2794)
			(end -0.12065 0.2794)
			(stroke
				(width 0.1)
				(type default)
			)
			(layer "F.Fab")
		)
		(fp_line
			(start -0.12065 -0.2794)
			(end 0.12065 -0.2794)
			(stroke
				(width 0.1)
				(type default)
			)
			(layer "F.Fab")
		)
		(fp_line
			(start 0.12065 -0.2794)
			(end 0.12065 -0.3048)
			(stroke
				(width 0.1)
				(type default)
			)
			(layer "F.Fab")
		)
		(fp_line
			(start 0.12065 -0.3048)
			(end 0.67945 -0.3048)
			(stroke
				(width 0.1)
				(type default)
			)
			(layer "F.Fab")
		)
		(fp_line
			(start 0.67945 -0.3048)
			(end 0.67945 0.3048)
			(stroke
				(width 0.1)
				(type default)
			)
			(layer "F.Fab")
		)
		(fp_line
			(start -0.67945 -0.305054)
			(end -0.12065 -0.305054)
			(stroke
				(width 0.1)
				(type default)
			)
			(layer "F.Fab")
		)
		(fp_line
			(start -0.12065 -0.305054)
			(end -0.12065 -0.2794)
			(stroke
				(width 0.1)
				(type default)
			)
			(layer "F.Fab")
		)
		(pad "1" smd circle
			(at -0.40005 0 270)
			(size 0 0)
			(layers "F.Cu" "F.Mask" "F.Paste")
			(net "FM_CPU1_SKTOCC_LVT3_N")
		)
		(pad "2" smd circle
			(at 0.40005 0 270)
			(size 0 0)
			(layers "F.Cu" "F.Mask" "F.Paste")
			(net "FM_CPU1_SKTOCC_LVT3_PLD_N")
		)
	)
)
